(kicad_pcb
	(version 20240108)
	(generator "pcbnew")
	(generator_version "8.0")
	(general
		(thickness 1.62)
		(legacy_teardrops no)
	)
	(paper "A4")
	(title_block
		(title "Jetson Orin Baseboard")
		(date "2025-03-12")
		(rev "1.3.4")
		(company "Antmicro Ltd")
		(comment 1 "www.antmicro.com")
		(comment 9 "footprints 423-427 of 677")
	)
	(layers
		(0 "F.Cu" signal)
		(1 "In1.Cu" signal)
		(2 "In2.Cu" signal)
		(3 "In3.Cu" signal)
		(4 "In4.Cu" jumper)
		(5 "In5.Cu" signal)
		(6 "In6.Cu" signal)
		(31 "B.Cu" signal)
		(32 "B.Adhes" user "B.Adhesive")
		(33 "F.Adhes" user "F.Adhesive")
		(34 "B.Paste" user)
		(35 "F.Paste" user)
		(36 "B.SilkS" user "B.Silkscreen")
		(37 "F.SilkS" user "F.Silkscreen")
		(38 "B.Mask" user)
		(39 "F.Mask" user)
		(40 "Dwgs.User" user "User.Drawings")
		(41 "Cmts.User" user "User.Comments")
		(42 "Eco1.User" user "User.Eco1")
		(43 "Eco2.User" user "User.Eco2")
		(44 "Edge.Cuts" user)
		(45 "Margin" user)
		(46 "B.CrtYd" user "B.Courtyard")
		(47 "F.CrtYd" user "F.Courtyard")
		(48 "B.Fab" user)
		(49 "F.Fab" user)
	)
	(footprint "antmicro-footprints:R_0402_1005Metric"
		(layer "B.Cu")
		(at 108.7 110.3)
		(descr "Resistor SMD 0402")
		(tags "resistor SMD 0402")
		(property "Reference" "R61"
			(at 2.97 0.52 180)
			(layer "B.SilkS")
			(effects
				(font
					(size 0.7 0.7)
					(thickness 0.15)
				)
				(justify left bottom mirror)
			)
		)
		(property "Value" "R_200k_0402"
			(at 0 -1.4 180)
			(layer "B.Fab")
			(effects
				(font
					(size 0.7 0.7)
					(thickness 0.15)
				)
				(justify left bottom mirror)
			)
		)
		(property "Footprint" "antmicro-footprints:R_0402_1005Metric"
			(at 0 0 0)
			(layer "F.Fab")
			(hide yes)
			(effects
				(font
					(size 1.27 1.27)
					(thickness 0.15)
				)
			)
		)
		(property "Datasheet" "https://www.bourns.com/docs/product-datasheets/cr.pdf"
			(at 0 0 0)
			(layer "F.Fab")
			(hide yes)
			(effects
				(font
					(size 1.27 1.27)
					(thickness 0.15)
				)
			)
		)
		(property "Author" "Antmicro"
			(at 0 0 0)
			(layer "B.Fab")
			(hide yes)
			(effects
				(font
					(size 1 1)
					(thickness 0.15)
				)
				(justify mirror)
			)
		)
		(property "License" "Apache-2.0"
			(at 0 0 0)
			(layer "B.Fab")
			(hide yes)
			(effects
				(font
					(size 1 1)
					(thickness 0.15)
				)
				(justify mirror)
			)
		)
		(property "MPN" "CR0402-FX-2003GLF"
			(at 0 0 0)
			(layer "B.Fab")
			(hide yes)
			(effects
				(font
					(size 1 1)
					(thickness 0.15)
				)
				(justify mirror)
			)
		)
		(property "Manufacturer" "Bourns"
			(at 0 0 0)
			(layer "B.Fab")
			(hide yes)
			(effects
				(font
					(size 1 1)
					(thickness 0.15)
				)
				(justify mirror)
			)
		)
		(property "Tolerance" "1%"
			(at 0 0 0)
			(layer "B.Fab")
			(hide yes)
			(effects
				(font
					(size 1 1)
					(thickness 0.15)
				)
				(justify mirror)
			)
		)
		(property "Val" "200k"
			(at 0 0 0)
			(layer "B.Fab")
			(hide yes)
			(effects
				(font
					(size 1 1)
					(thickness 0.15)
				)
				(justify mirror)
			)
		)
		(sheetname "USB3")
		(sheetfile "usb3.kicad_sch")
		(attr smd)
		(fp_rect
			(start -0.925 0.47)
			(end 0.925 -0.47)
			(stroke
				(width 0.05)
				(type default)
			)
			(fill none)
			(layer "B.CrtYd")
		)
		(fp_rect
			(start -0.5 0.25)
			(end 0.5 -0.25)
			(stroke
				(width 0.15)
				(type solid)
			)
			(fill none)
			(layer "B.Fab")
		)
		(fp_text user "Author: Antmicro"
			(at -0.95 -4.169 180)
			(layer "B.Fab")
			(hide yes)
			(effects
				(font
					(size 0.7 0.7)
					(thickness 0.15)
				)
				(justify left bottom mirror)
			)
		)
		(fp_text user "${REFERENCE}"
			(at -0.95 -3.168 180)
			(layer "B.Fab")
			(hide yes)
			(effects
				(font
					(size 0.7 0.7)
					(thickness 0.15)
				)
				(justify left bottom mirror)
			)
		)
		(fp_text user "License: Apache-2.0"
			(at -0.95 -5.169 180)
			(layer "B.Fab")
			(hide yes)
			(effects
				(font
					(size 0.7 0.7)
					(thickness 0.15)
				)
				(justify left bottom mirror)
			)
		)
		(pad "1" smd roundrect
			(at -0.48 0)
			(size 0.59 0.64)
			(layers "B.Cu" "B.Paste" "B.Mask")
			(roundrect_rratio 0.25)
			(net 1 "GND")
			(pintype "passive")
		)
		(pad "2" smd roundrect
			(at 0.48 0)
			(size 0.59 0.64)
			(layers "B.Cu" "B.Paste" "B.Mask")
			(roundrect_rratio 0.25)
			(net 632 "Net-(Q19-G)")
			(pintype "passive")
		)
	)
	(footprint "antmicro-footprints:R_0402_1005Metric"
		(layer "B.Cu")
		(at 47.55 120.65 180)
		(descr "Resistor SMD 0402")
		(tags "resistor SMD 0402")
		(property "Reference" "R270"
			(at 6.93 1.04 0)
			(layer "B.SilkS")
			(effects
				(font
					(size 0.7 0.7)
					(thickness 0.15)
				)
				(justify left bottom mirror)
			)
		)
		(property "Value" "R_100k_0402"
			(at -1.011843 -1.772047 0)
			(layer "B.Fab")
			(effects
				(font
					(size 0.7 0.7)
					(thickness 0.15)
				)
				(justify left bottom mirror)
			)
		)
		(property "Footprint" "antmicro-footprints:R_0402_1005Metric"
			(at 0 0 180)
			(layer "F.Fab")
			(hide yes)
			(effects
				(font
					(size 1.27 1.27)
					(thickness 0.15)
				)
			)
		)
		(property "Datasheet" "https://www.bourns.com/docs/product-datasheets/cr.pdf"
			(at 0 0 180)
			(layer "F.Fab")
			(hide yes)
			(effects
				(font
					(size 1.27 1.27)
					(thickness 0.15)
				)
			)
		)
		(property "Author" "Antmicro"
			(at 95.1 241.3 0)
			(layer "B.Fab")
			(hide yes)
			(effects
				(font
					(size 1 1)
					(thickness 0.15)
				)
				(justify mirror)
			)
		)
		(property "License" "Apache-2.0"
			(at 95.1 241.3 0)
			(layer "B.Fab")
			(hide yes)
			(effects
				(font
					(size 1 1)
					(thickness 0.15)
				)
				(justify mirror)
			)
		)
		(property "MPN" "CR0402-FX-1003GLF"
			(at 95.1 241.3 0)
			(layer "B.Fab")
			(hide yes)
			(effects
				(font
					(size 1 1)
					(thickness 0.15)
				)
				(justify mirror)
			)
		)
		(property "Manufacturer" "Bourns"
			(at 95.1 241.3 0)
			(layer "B.Fab")
			(hide yes)
			(effects
				(font
					(size 1 1)
					(thickness 0.15)
				)
				(justify mirror)
			)
		)
		(property "Tolerance" "1%"
			(at 95.1 241.3 0)
			(layer "B.Fab")
			(hide yes)
			(effects
				(font
					(size 1 1)
					(thickness 0.15)
				)
				(justify mirror)
			)
		)
		(property "Val" "100k"
			(at 95.1 241.3 0)
			(layer "B.Fab")
			(hide yes)
			(effects
				(font
					(size 1 1)
					(thickness 0.15)
				)
				(justify mirror)
			)
		)
		(sheetname "USB Debug, DP")
		(sheetfile "usb.kicad_sch")
		(attr smd)
		(fp_rect
			(start -0.925 0.47)
			(end 0.925 -0.47)
			(stroke
				(width 0.05)
				(type default)
			)
			(fill none)
			(layer "B.CrtYd")
		)
		(fp_rect
			(start -0.5 0.25)
			(end 0.5 -0.25)
			(stroke
				(width 0.15)
				(type solid)
			)
			(fill none)
			(layer "B.Fab")
		)
		(fp_text user "License: Apache-2.0"
			(at -0.95 -5.169 0)
			(layer "B.Fab")
			(hide yes)
			(effects
				(font
					(size 0.7 0.7)
					(thickness 0.15)
				)
				(justify left bottom mirror)
			)
		)
		(fp_text user "Author: Antmicro"
			(at -0.95 -4.169 0)
			(layer "B.Fab")
			(hide yes)
			(effects
				(font
					(size 0.7 0.7)
					(thickness 0.15)
				)
				(justify left bottom mirror)
			)
		)
		(fp_text user "${REFERENCE}"
			(at -0.95 -3.168 0)
			(layer "B.Fab")
			(hide yes)
			(effects
				(font
					(size 0.7 0.7)
					(thickness 0.15)
				)
				(justify left bottom mirror)
			)
		)
		(pad "1" smd roundrect
			(at -0.48 0 180)
			(size 0.59 0.64)
			(layers "B.Cu" "B.Paste" "B.Mask")
			(roundrect_rratio 0.25)
			(net 397 "/USB Debug, DP/FTDI_CBUS_EN")
			(pintype "passive")
		)
		(pad "2" smd roundrect
			(at 0.48 0 180)
			(size 0.59 0.64)
			(layers "B.Cu" "B.Paste" "B.Mask")
			(roundrect_rratio 0.25)
			(net 185 "/USB Debug, DP/FTDI_3V3")
			(pintype "passive")
		)
	)
	(footprint "antmicro-footprints:C_0402_1005Metric"
		(layer "B.Cu")
		(at 66.6 86.8 90)
		(descr "Capacitor SMD 0402")
		(tags "capacitor SMD 0402")
		(property "Reference" "C97"
			(at 0.92 -0.48 -90)
			(layer "B.SilkS")
			(effects
				(font
					(size 0.7 0.7)
					(thickness 0.15)
				)
				(justify left bottom mirror)
			)
		)
		(property "Value" "C_100n_0402"
			(at 0 -1.4 -90)
			(layer "B.Fab")
			(effects
				(font
					(size 0.7 0.7)
					(thickness 0.15)
				)
				(justify left bottom mirror)
			)
		)
		(property "Footprint" "antmicro-footprints:C_0402_1005Metric"
			(at 0 0 90)
			(layer "F.Fab")
			(hide yes)
			(effects
				(font
					(size 1.27 1.27)
					(thickness 0.15)
				)
			)
		)
		(property "Datasheet" "https://www.murata.com/products/productdetail?partno=GRM155R61H104KE14%23"
			(at 0 0 90)
			(layer "F.Fab")
			(hide yes)
			(effects
				(font
					(size 1.27 1.27)
					(thickness 0.15)
				)
			)
		)
		(property "Author" "Antmicro"
			(at 153.4 20.2 0)
			(layer "B.Fab")
			(hide yes)
			(effects
				(font
					(size 1 1)
					(thickness 0.15)
				)
				(justify mirror)
			)
		)
		(property "Dielectric" "X5R"
			(at 153.4 20.2 0)
			(layer "B.Fab")
			(hide yes)
			(effects
				(font
					(size 1 1)
					(thickness 0.15)
				)
				(justify mirror)
			)
		)
		(property "License" "Apache-2.0"
			(at 153.4 20.2 0)
			(layer "B.Fab")
			(hide yes)
			(effects
				(font
					(size 1 1)
					(thickness 0.15)
				)
				(justify mirror)
			)
		)
		(property "MPN" "GRM155R61H104KE14D"
			(at 153.4 20.2 0)
			(layer "B.Fab")
			(hide yes)
			(effects
				(font
					(size 1 1)
					(thickness 0.15)
				)
				(justify mirror)
			)
		)
		(property "Manufacturer" "Murata"
			(at 153.4 20.2 0)
			(layer "B.Fab")
			(hide yes)
			(effects
				(font
					(size 1 1)
					(thickness 0.15)
				)
				(justify mirror)
			)
		)
		(property "Val" "100n"
			(at 153.4 20.2 0)
			(layer "B.Fab")
			(hide yes)
			(effects
				(font
					(size 1 1)
					(thickness 0.15)
				)
				(justify mirror)
			)
		)
		(property "Voltage" "50V"
			(at 153.4 20.2 0)
			(layer "B.Fab")
			(hide yes)
			(effects
				(font
					(size 1 1)
					(thickness 0.15)
				)
				(justify mirror)
			)
		)
		(sheetname "CSI")
		(sheetfile "csi.kicad_sch")
		(attr smd)
		(fp_rect
			(start -0.925 0.47)
			(end 0.925 -0.47)
			(stroke
				(width 0.05)
				(type default)
			)
			(fill none)
			(layer "B.CrtYd")
		)
		(fp_line
			(start 0.504 -0.248)
			(end 0.504 0.25)
			(stroke
				(width 0.15)
				(type solid)
			)
			(layer "B.Fab")
		)
		(fp_line
			(start -0.494 -0.248)
			(end 0.504 -0.248)
			(stroke
				(width 0.15)
				(type solid)
			)
			(layer "B.Fab")
		)
		(fp_line
			(start 0.504 0.25)
			(end -0.494 0.25)
			(stroke
				(width 0.15)
				(type solid)
			)
			(layer "B.Fab")
		)
		(fp_line
			(start -0.494 0.25)
			(end -0.494 -0.248)
			(stroke
				(width 0.15)
				(type solid)
			)
			(layer "B.Fab")
		)
		(fp_text user "Author: Antmicro"
			(at -0.932 -4.17 -90)
			(layer "B.Fab")
			(hide yes)
			(effects
				(font
					(size 0.7 0.7)
					(thickness 0.15)
				)
				(justify left bottom mirror)
			)
		)
		(fp_text user "${REFERENCE}"
			(at -0.932 -3.168 -90)
			(layer "B.Fab")
			(hide yes)
			(effects
				(font
					(size 0.7 0.7)
					(thickness 0.15)
				)
				(justify left bottom mirror)
			)
		)
		(fp_text user "License: Apache-2.0"
			(at -0.932 -5.17 -90)
			(layer "B.Fab")
			(hide yes)
			(effects
				(font
					(size 0.7 0.7)
					(thickness 0.15)
				)
				(justify left bottom mirror)
			)
		)
		(pad "1" smd roundrect
			(at -0.48 0 90)
			(size 0.59 0.64)
			(layers "B.Cu" "B.Paste" "B.Mask")
			(roundrect_rratio 0.25)
			(net 1 "GND")
			(pintype "passive")
		)
		(pad "2" smd roundrect
			(at 0.48 0 90)
			(size 0.59 0.64)
			(layers "B.Cu" "B.Paste" "B.Mask")
			(roundrect_rratio 0.25)
			(net 112 "+1V8")
			(pintype "passive")
		)
	)
	(footprint "antmicro-footprints:XDFN-2_1x0.60mm"
		(layer "B.Cu")
		(at 117 71.1)
		(property "Reference" "D16"
			(at -0.53 1.4 180)
			(layer "B.SilkS")
			(effects
				(font
					(size 0.7 0.7)
					(thickness 0.15)
				)
				(justify right bottom mirror)
			)
		)
		(property "Value" "TPD1E0B04_XDFN-2"
			(at 0 -1.5 180)
			(layer "B.Fab")
			(effects
				(font
					(size 0.7 0.7)
					(thickness 0.15)
				)
				(justify left bottom mirror)
			)
		)
		(property "Footprint" "antmicro-footprints:XDFN-2_1x0.60mm"
			(at 0 0 0)
			(layer "F.Fab")
			(hide yes)
			(effects
				(font
					(size 1.27 1.27)
					(thickness 0.15)
				)
			)
		)
		(property "Datasheet" "https://www.ti.com/general/docs/suppproductinfo.tsp?distId=26&gotoUrl=https://www.ti.com/lit/gpn/tpd1e0b04"
			(at 0 0 0)
			(layer "F.Fab")
			(hide yes)
			(effects
				(font
					(size 1.27 1.27)
					(thickness 0.15)
				)
			)
		)
		(property "MPN" "TPD1E0B04DPYR"
			(at 0 0 0)
			(layer "B.Fab")
			(hide yes)
			(effects
				(font
					(size 1 1)
					(thickness 0.15)
				)
				(justify mirror)
			)
		)
		(property "Manufacturer" "Texas Instruments"
			(at 0 0 0)
			(layer "B.Fab")
			(hide yes)
			(effects
				(font
					(size 1 1)
					(thickness 0.15)
				)
				(justify mirror)
			)
		)
		(property "Author" "Antmicro"
			(at 0 0 0)
			(layer "B.Fab")
			(hide yes)
			(effects
				(font
					(size 1 1)
					(thickness 0.15)
				)
				(justify mirror)
			)
		)
		(property "License" "Apache-2.0"
			(at 0 0 0)
			(layer "B.Fab")
			(hide yes)
			(effects
				(font
					(size 1 1)
					(thickness 0.15)
				)
				(justify mirror)
			)
		)
		(sheetname "Peripherals")
		(sheetfile "peripherals.kicad_sch")
		(attr smd)
		(fp_rect
			(start -0.725 0.475)
			(end 0.725 -0.475)
			(stroke
				(width 0.05)
				(type solid)
			)
			(fill none)
			(layer "B.CrtYd")
		)
		(fp_rect
			(start -0.55 0.35)
			(end 0.55 -0.35)
			(stroke
				(width 0.15)
				(type solid)
			)
			(fill none)
			(layer "B.Fab")
		)
		(fp_text user "Author: Antmicro"
			(at -0.8 -4.4 180)
			(layer "B.Fab")
			(hide yes)
			(effects
				(font
					(size 0.7 0.7)
					(thickness 0.15)
				)
				(justify left bottom mirror)
			)
		)
		(fp_text user "${REFERENCE}"
			(at -0.8 -3.2 180)
			(layer "B.Fab")
			(hide yes)
			(effects
				(font
					(size 0.7 0.7)
					(thickness 0.15)
				)
				(justify left bottom mirror)
			)
		)
		(fp_text user "License: Apache-2.0"
			(at -0.8 -5.6 180)
			(layer "B.Fab")
			(hide yes)
			(effects
				(font
					(size 0.7 0.7)
					(thickness 0.15)
				)
				(justify left bottom mirror)
			)
		)
		(pad "1" smd roundrect
			(at -0.351 0)
			(size 0.3 0.5)
			(layers "B.Cu" "B.Paste" "B.Mask")
			(roundrect_rratio 0.25)
			(net 107 "USBSS1_RX_N")
			(pinfunction "C")
			(pintype "passive")
		)
		(pad "2" smd roundrect
			(at 0.349 0)
			(size 0.3 0.5)
			(layers "B.Cu" "B.Paste" "B.Mask")
			(roundrect_rratio 0.25)
			(net 1 "GND")
			(pinfunction "A")
			(pintype "passive")
		)
	)
	(footprint "antmicro-footprints:R_0402_1005Metric"
		(layer "B.Cu")
		(at 57.425 94.15 180)
		(descr "Resistor SMD 0402")
		(tags "resistor SMD 0402")
		(property "Reference" "R181"
			(at -1.5 -0.54 0)
			(layer "B.SilkS")
			(effects
				(font
					(size 0.7 0.7)
					(thickness 0.15)
				)
				(justify left top mirror)
			)
		)
		(property "Value" "R_10k_0402"
			(at -1.011843 -1.772047 0)
			(layer "B.Fab")
			(effects
				(font
					(size 0.7 0.7)
					(thickness 0.15)
				)
				(justify left top mirror)
			)
		)
		(property "Footprint" "antmicro-footprints:R_0402_1005Metric"
			(at 0 0 0)
			(layer "B.Fab")
			(hide yes)
			(effects
				(font
					(size 1.27 1.27)
					(thickness 0.15)
				)
				(justify mirror)
			)
		)
		(property "Datasheet" "https://www.bourns.com/docs/product-datasheets/cr.pdf"
			(at 0 0 0)
			(layer "B.Fab")
			(hide yes)
			(effects
				(font
					(size 1.27 1.27)
					(thickness 0.15)
				)
				(justify mirror)
			)
		)
		(property "Author" "Antmicro"
			(at 117.96 -178.14 0)
			(layer "B.Fab")
			(hide yes)
			(effects
				(font
					(size 1 1)
					(thickness 0.15)
				)
				(justify mirror)
			)
		)
		(property "License" "Apache-2.0"
			(at 117.96 -178.14 0)
			(layer "B.Fab")
			(hide yes)
			(effects
				(font
					(size 1 1)
					(thickness 0.15)
				)
				(justify mirror)
			)
		)
		(property "MPN" "CR0402-FX-1002GLF"
			(at 117.96 -178.14 0)
			(layer "B.Fab")
			(hide yes)
			(effects
				(font
					(size 1 1)
					(thickness 0.15)
				)
				(justify mirror)
			)
		)
		(property "Manufacturer" "Bourns"
			(at 117.96 -178.14 0)
			(layer "B.Fab")
			(hide yes)
			(effects
				(font
					(size 1 1)
					(thickness 0.15)
				)
				(justify mirror)
			)
		)
		(property "Tolerance" "1%"
			(at 117.96 -178.14 0)
			(layer "B.Fab")
			(hide yes)
			(effects
				(font
					(size 1 1)
					(thickness 0.15)
				)
				(justify mirror)
			)
		)
		(property "Val" "10k"
			(at 117.96 -178.14 0)
			(layer "B.Fab")
			(hide yes)
			(effects
				(font
					(size 1 1)
					(thickness 0.15)
				)
				(justify mirror)
			)
		)
		(sheetname "Supply")
		(sheetfile "supply.kicad_sch")
		(attr smd)
		(fp_rect
			(start -0.925 0.47)
			(end 0.925 -0.47)
			(stroke
				(width 0.05)
				(type default)
			)
			(fill none)
			(layer "B.CrtYd")
		)
		(fp_rect
			(start -0.5 0.25)
			(end 0.5 -0.25)
			(stroke
				(width 0.15)
				(type solid)
			)
			(fill none)
			(layer "B.Fab")
		)
		(fp_text user "License: Apache-2.0"
			(at -0.95 -5.169 0)
			(layer "B.Fab")
			(hide yes)
			(effects
				(font
					(size 0.7 0.7)
					(thickness 0.15)
				)
				(justify left top mirror)
			)
		)
		(fp_text user "Author: Antmicro"
			(at -0.95 -4.169 0)
			(layer "B.Fab")
			(hide yes)
			(effects
				(font
					(size 0.7 0.7)
					(thickness 0.15)
				)
				(justify left top mirror)
			)
		)
		(fp_text user "${REFERENCE}"
			(at -0.95 -3.168 0)
			(layer "B.Fab")
			(hide yes)
			(effects
				(font
					(size 0.7 0.7)
					(thickness 0.15)
				)
				(justify left top mirror)
			)
		)
		(pad "1" smd roundrect
			(at -0.48 0 180)
			(size 0.59 0.64)
			(layers "B.Cu" "B.Paste" "B.Mask")
			(roundrect_rratio 0.25)
			(net 768 "/Supply/5V_GATE")
			(pintype "passive")
		)
		(pad "2" smd roundrect
			(at 0.48 0 180)
			(size 0.59 0.64)
			(layers "B.Cu" "B.Paste" "B.Mask")
			(roundrect_rratio 0.25)
			(net 787 "+5V_SoM")
			(pintype "passive")
		)
	)
)
